FILE_TYPE = CONNECTIVITY;
{Allegro Design Entry HDL 17.2-2016 S081 (4005846) 1/11/2022}
"PAGE_NUMBER" = 19;
0"NC";
1"M_J_CPU0_SA_DQ<31:0>";
2"M_J_CPU0_SB_DQ<31:0>";
3"M_J_CPU0_SA_CB<7:0>";
4"M_J_CPU0_SB_CB<7:0>";
5"M_J_CPU0_SA_DQS_DP<9:0>";
6"M_J_CPU0_SB_DQS_DP<9:0>";
7"M_J_CPU0_SB_CA<6:0>";
8"M_J_CPU0_SA_CA<6:0>";
9"M_J_CPU0_SA_DQS_DN<9:0>";
10"M_J_CPU0_SB_DQS_DN<9:0>";
11"M_J_CPU0_ALERT_N";
12"TP_M_J_CPU0_SA_TEST39J";
13"M_J_CPU0_ALERT_R_N";
14"M_J_CPU0_CLK_DP<0>";
15"M_J_CPU0_CLK_DN<0>";
16"M_J_CPU0_SA_CS_N<0>";
17"M_J_CPU0_SA_PAR";
18"M_J_CPU0_SA_CS_N<1>";
19"M_J_CPU0_SA_RSP<0>";
20"M_J_CPU0_SB_CS_N<0>";
21"M_J_CPU0_SB_CS_N<1>";
22"M_J_CPU0_SB_RSP<0>";
23"M_J_CPU0_SB_PAR";
24"M_J_CPU0_RESET_N";
25"M_J_CPU0_SA_CA<5>";
26"M_J_CPU0_SA_CA<6>";
27"M_J_CPU0_SA_CA<0>";
28"M_J_CPU0_SA_CA<1>";
29"M_J_CPU0_SA_CA<2>";
30"M_J_CPU0_SA_CA<3>";
31"M_J_CPU0_SA_CA<4>";
32"M_J_CPU0_SB_CA<0>";
33"M_J_CPU0_SB_CA<1>";
34"M_J_CPU0_SB_CA<2>";
35"M_J_CPU0_SB_CA<3>";
36"M_J_CPU0_SB_CA<4>";
37"M_J_CPU0_SB_CA<5>";
38"M_J_CPU0_SB_CA<6>";
39"M_J_CPU0_SB_DQS_DN<9>";
40"M_J_CPU0_SB_DQS_DP<9>";
41"M_J_CPU0_SB_DQS_DN<4>";
42"M_J_CPU0_SB_DQS_DN<0>";
43"M_J_CPU0_SA_DQS_DN<9>";
44"M_J_CPU0_SB_DQS_DN<1>";
45"M_J_CPU0_SB_DQS_DN<2>";
46"M_J_CPU0_SB_DQS_DN<3>";
47"M_J_CPU0_SB_DQS_DN<5>";
48"M_J_CPU0_SB_DQS_DN<6>";
49"M_J_CPU0_SB_DQS_DN<7>";
50"M_J_CPU0_SB_DQS_DN<8>";
51"M_J_CPU0_SB_DQS_DP<5>";
52"M_J_CPU0_SB_DQS_DP<4>";
53"M_J_CPU0_SB_DQS_DP<6>";
54"M_J_CPU0_SB_DQS_DP<7>";
55"M_J_CPU0_SB_DQS_DP<8>";
56"M_J_CPU0_SA_DQS_DP<9>";
57"M_J_CPU0_SB_DQS_DP<0>";
58"M_J_CPU0_SB_DQS_DP<1>";
59"M_J_CPU0_SB_DQS_DP<2>";
60"M_J_CPU0_SB_DQS_DP<3>";
61"M_J_CPU0_SA_DQS_DN<4>";
62"M_J_CPU0_SA_DQS_DN<5>";
63"M_J_CPU0_SA_DQS_DN<7>";
64"M_J_CPU0_SA_DQS_DN<0>";
65"M_J_CPU0_SA_DQS_DN<1>";
66"M_J_CPU0_SA_DQS_DN<2>";
67"M_J_CPU0_SA_DQS_DN<3>";
68"M_J_CPU0_SA_DQS_DN<6>";
69"M_J_CPU0_SA_DQS_DN<8>";
70"M_J_CPU0_SA_DQS_DP<4>";
71"M_J_CPU0_SA_DQS_DP<8>";
72"M_J_CPU0_SA_DQS_DP<5>";
73"M_J_CPU0_SA_DQS_DP<6>";
74"M_J_CPU0_SA_DQS_DP<7>";
75"M_J_CPU0_SA_DQS_DP<0>";
76"M_J_CPU0_SA_DQS_DP<1>";
77"M_J_CPU0_SA_DQS_DP<2>";
78"M_J_CPU0_SA_DQS_DP<3>";
79"M_J_CPU0_SB_CB<0>";
80"M_J_CPU0_SB_CB<1>";
81"M_J_CPU0_SB_CB<2>";
82"M_J_CPU0_SB_CB<3>";
83"M_J_CPU0_SB_CB<4>";
84"M_J_CPU0_SB_CB<5>";
85"M_J_CPU0_SB_CB<6>";
86"M_J_CPU0_SB_CB<7>";
87"M_J_CPU0_SA_CB<0>";
88"M_J_CPU0_SA_CB<1>";
89"M_J_CPU0_SA_CB<2>";
90"M_J_CPU0_SA_CB<3>";
91"M_J_CPU0_SA_CB<4>";
92"M_J_CPU0_SA_CB<5>";
93"M_J_CPU0_SA_CB<6>";
94"M_J_CPU0_SA_CB<7>";
95"M_J_CPU0_SB_DQ<21>";
96"M_J_CPU0_SB_DQ<22>";
97"M_J_CPU0_SB_DQ<23>";
98"M_J_CPU0_SB_DQ<24>";
99"M_J_CPU0_SB_DQ<25>";
100"M_J_CPU0_SB_DQ<26>";
101"M_J_CPU0_SB_DQ<27>";
102"M_J_CPU0_SB_DQ<28>";
103"M_J_CPU0_SB_DQ<29>";
104"M_J_CPU0_SB_DQ<30>";
105"M_J_CPU0_SB_DQ<31>";
106"M_J_CPU0_SB_DQ<7>";
107"M_J_CPU0_SB_DQ<6>";
108"M_J_CPU0_SB_DQ<5>";
109"M_J_CPU0_SB_DQ<3>";
110"M_J_CPU0_SB_DQ<4>";
111"M_J_CPU0_SB_DQ<8>";
112"M_J_CPU0_SB_DQ<9>";
113"M_J_CPU0_SB_DQ<10>";
114"M_J_CPU0_SB_DQ<11>";
115"M_J_CPU0_SB_DQ<12>";
116"M_J_CPU0_SB_DQ<13>";
117"M_J_CPU0_SB_DQ<14>";
118"M_J_CPU0_SB_DQ<15>";
119"M_J_CPU0_SB_DQ<16>";
120"M_J_CPU0_SB_DQ<17>";
121"M_J_CPU0_SB_DQ<18>";
122"M_J_CPU0_SB_DQ<19>";
123"M_J_CPU0_SB_DQ<20>";
124"M_J_CPU0_SA_DQ<31>";
125"M_J_CPU0_SB_DQ<0>";
126"M_J_CPU0_SA_DQ<22>";
127"M_J_CPU0_SA_DQ<16>";
128"M_J_CPU0_SA_DQ<17>";
129"M_J_CPU0_SA_DQ<18>";
130"M_J_CPU0_SA_DQ<19>";
131"M_J_CPU0_SA_DQ<20>";
132"M_J_CPU0_SA_DQ<21>";
133"M_J_CPU0_SA_DQ<23>";
134"M_J_CPU0_SA_DQ<24>";
135"M_J_CPU0_SA_DQ<25>";
136"M_J_CPU0_SA_DQ<26>";
137"M_J_CPU0_SA_DQ<27>";
138"M_J_CPU0_SA_DQ<28>";
139"M_J_CPU0_SA_DQ<29>";
140"M_J_CPU0_SA_DQ<30>";
141"M_J_CPU0_SB_DQ<1>";
142"M_J_CPU0_SB_DQ<2>";
143"M_J_CPU0_SA_DQ<0>";
144"M_J_CPU0_SA_DQ<1>";
145"M_J_CPU0_SA_DQ<2>";
146"M_J_CPU0_SA_DQ<3>";
147"M_J_CPU0_SA_DQ<4>";
148"M_J_CPU0_SA_DQ<5>";
149"M_J_CPU0_SA_DQ<6>";
150"M_J_CPU0_SA_DQ<7>";
151"M_J_CPU0_SA_DQ<8>";
152"M_J_CPU0_SA_DQ<9>";
153"M_J_CPU0_SA_DQ<10>";
154"M_J_CPU0_SA_DQ<11>";
155"M_J_CPU0_SA_DQ<12>";
156"M_J_CPU0_SA_DQ<13>";
157"M_J_CPU0_SA_DQ<14>";
158"M_J_CPU0_SA_DQ<15>";
%"GENOA_SP5"
"10","(-4525,3625)","0","pure_quanta","I159";
;
LOCATION"U25"
$SEC"10"
CDS_SEC"10"
PART_TYPE"SMLF"
MATERIAL"IO"
VALUE"SOCKET6096_13568-001"
PART_NUMBER"DGA^6000030"
CDS_LIB"pure_quanta"
CDS_LMAN_SYM_OUTLINE"-650,2525,650,-2525"
NEEDS_NO_SIZE"TRUE";
"TEST39J"
$PN"BF18"12;
"MJB_DATA7"
$PN"CH18"106;
"MJB_DATA6"
$PN"CG16"107;
"MJB_DATA5"
$PN"CG17"108;
"MJB_DQS_H5"
$PN"CF18"51;
"MJB_DQS_L4"
$PN"BW17"41;
"MJB_DQS_L0"
$PN"CE16"42;
"MJA_DATA31"
$PN"AJ17"124;
"MJB_DATA0"
$PN"CB16"125;
"MJB_DATA3"
$PN"CD18"109;
"MJB_DATA4"
$PN"CF16"110;
"MJA_DQS_H4"
$PN"AL16"70;
"MJA_DQS_H8"
$PN"AG17"71;
"MJA_DQS_L4"
$PN"AM16"61;
"MJA_DQS_L5"
$PN"H18"62;
"MJA_DQS_L7"
$PN"Y18"63;
"MJA_DATA22"
$PN"AB16"126;
"MJA_CA5"
$PN"BB16"25;
"MJA_CA6"
$PN"BB18"26;
"MJ0_CLK_H"
$PN"BC16"14;
"MJ0_CLK_L"
$PN"BD16"15;
"MJ1_CLK_H"
$PN"BF16"0;
"MJ1_CLK_L"
$PN"BG16"0;
"MJA0_CS_L0"
$PN"AU16"16;
"MJA0_CS_L1"
$PN"AV18"18;
"MJA0_RSP_L"
$PN"BN17"19;
"MJA1_CS_L0"
$PN"AV16"0;
"MJA1_CS_L1"
$PN"AW17"0;
"MJA1_RSP_L"
$PN"BP18"0;
"MJA_CA0"
$PN"AW16"27;
"MJA_CA1"
$PN"AY16"28;
"MJA_CA2"
$PN"AY18"29;
"MJA_CA3"
$PN"BA17"30;
"MJA_CA4"
$PN"BA16"31;
"MJA_CHECK0"
$PN"AJ16"87;
"MJA_CHECK1"
$PN"AK18"88;
"MJA_CHECK2"
$PN"AK16"89;
"MJA_CHECK3"
$PN"AL17"90;
"MJA_CHECK4"
$PN"AN16"91;
"MJA_CHECK5"
$PN"AP18"92;
"MJA_CHECK6"
$PN"AP16"93;
"MJA_CHECK7"
$PN"AR17"94;
"MJA_DATA0"
$PN"E16"143;
"MJA_DATA1"
$PN"F18"144;
"MJA_DATA2"
$PN"F16"145;
"MJA_DATA3"
$PN"G17"146;
"MJA_DATA4"
$PN"J16"147;
"MJA_DATA5"
$PN"K18"148;
"MJA_DATA6"
$PN"K16"149;
"MJA_DATA7"
$PN"L17"150;
"MJA_DATA8"
$PN"L16"151;
"MJA_DATA9"
$PN"M18"152;
"MJA_DATA10"
$PN"M16"153;
"MJA_DATA11"
$PN"N17"154;
"MJA_DATA12"
$PN"R16"155;
"MJA_DATA13"
$PN"T18"156;
"MJA_DATA14"
$PN"T16"157;
"MJA_DATA15"
$PN"U17"158;
"MJA_DATA16"
$PN"U16"127;
"MJA_DATA17"
$PN"V18"128;
"MJA_DATA18"
$PN"V16"129;
"MJA_DATA19"
$PN"W17"130;
"MJA_DATA20"
$PN"AA16"131;
"MJA_DATA21"
$PN"AB18"132;
"MJA_DATA23"
$PN"AC17"133;
"MJA_DATA24"
$PN"AC16"134;
"MJA_DATA25"
$PN"AD18"135;
"MJA_DATA26"
$PN"AD16"136;
"MJA_DATA27"
$PN"AE17"137;
"MJA_DATA28"
$PN"AG16"138;
"MJA_DATA29"
$PN"AH18"139;
"MJA_DATA30"
$PN"AH16"140;
"MJA_DQS_H0"
$PN"G16"75;
"MJA_DQS_H1"
$PN"N16"76;
"MJA_DQS_H2"
$PN"W16"77;
"MJA_DQS_H3"
$PN"AE16"78;
"MJA_DQS_H5"
$PN"J17"72;
"MJA_DQS_H6"
$PN"R17"73;
"MJA_DQS_H7"
$PN"AA17"74;
"MJA_DQS_H9"
$PN"AN17"56;
"MJA_DQS_L0"
$PN"H16"64;
"MJA_DQS_L1"
$PN"P16"65;
"MJA_DQS_L2"
$PN"Y16"66;
"MJA_DQS_L3"
$PN"AF16"67;
"MJA_DQS_L6"
$PN"P18"68;
"MJA_DQS_L8"
$PN"AF18"69;
"MJA_DQS_L9"
$PN"AM18"43;
"MJA_PAR"
$PN"BC17"17;
"MJB0_CS_L0"
$PN"BM18"20;
"MJB0_CS_L1"
$PN"BN16"21;
"MJB0_RSP_L"
$PN"BP16"22;
"MJB1_CS_L0"
$PN"BL16"0;
"MJB1_CS_L1"
$PN"BM16"0;
"MJB1_RSP_L"
$PN"BR16"0;
"MJB_CA0"
$PN"BG17"32;
"MJB_CA1"
$PN"BH18"33;
"MJB_CA2"
$PN"BH16"34;
"MJB_CA3"
$PN"BJ16"35;
"MJB_CA4"
$PN"BJ17"36;
"MJB_CA5"
$PN"BK18"37;
"MJB_CA6"
$PN"BK16"38;
"MJB_CHECK0"
$PN"BY16"79;
"MJB_CHECK1"
$PN"CA17"80;
"MJB_CHECK2"
$PN"CA16"81;
"MJB_CHECK3"
$PN"CB18"82;
"MJB_CHECK4"
$PN"BT16"83;
"MJB_CHECK5"
$PN"BU17"84;
"MJB_CHECK6"
$PN"BU16"85;
"MJB_CHECK7"
$PN"BV18"86;
"MJB_DATA1"
$PN"CC17"141;
"MJB_DATA2"
$PN"CC16"142;
"MJB_DATA8"
$PN"CH16"111;
"MJB_DATA9"
$PN"CJ17"112;
"MJB_DATA10"
$PN"CJ16"113;
"MJB_DATA11"
$PN"CK18"114;
"MJB_DATA12"
$PN"CM16"115;
"MJB_DATA13"
$PN"CN17"116;
"MJB_DATA14"
$PN"CN16"117;
"MJB_DATA15"
$PN"CP18"118;
"MJB_DATA16"
$PN"CP16"119;
"MJB_DATA17"
$PN"CR17"120;
"MJB_DATA18"
$PN"CR16"121;
"MJB_DATA19"
$PN"CT18"122;
"MJB_DATA20"
$PN"CV16"123;
"MJB_DATA21"
$PN"CW17"95;
"MJB_DATA22"
$PN"CW16"96;
"MJB_DATA23"
$PN"CY18"97;
"MJB_DATA24"
$PN"CY16"98;
"MJB_DATA25"
$PN"DA17"99;
"MJB_DATA26"
$PN"DA16"100;
"MJB_DATA27"
$PN"DB18"101;
"MJB_DATA28"
$PN"DD16"102;
"MJB_DATA29"
$PN"DE17"103;
"MJB_DATA30"
$PN"DE16"104;
"MJB_DATA31"
$PN"DF16"105;
"MJB_DQS_H0"
$PN"CD16"57;
"MJB_DQS_H1"
$PN"CK16"58;
"MJB_DQS_H2"
$PN"CT16"59;
"MJB_DQS_H3"
$PN"DB16"60;
"MJB_DQS_H4"
$PN"BY18"52;
"MJB_DQS_H6"
$PN"CM18"53;
"MJB_DQS_H7"
$PN"CV18"54;
"MJB_DQS_H8"
$PN"DD18"55;
"MJB_DQS_H9"
$PN"BV16"40;
"MJB_DQS_L1"
$PN"CL16"44;
"MJB_DQS_L2"
$PN"CU16"45;
"MJB_DQS_L3"
$PN"DC16"46;
"MJB_DQS_L5"
$PN"CE17"47;
"MJB_DQS_L6"
$PN"CL17"48;
"MJB_DQS_L7"
$PN"CU17"49;
"MJB_DQS_L8"
$PN"DC17"50;
"MJB_DQS_L9"
$PN"BW16"39;
"MJB_PAR"
$PN"BL17"23;
"MJ_ALERT_L"
$PN"AT18"13;
"MJ_RESET_L"
$PN"AU17"24;
%"TAP"
"1","(-3250,5900)","0","mstr_standard","I162";
;
CDS_LIB"mstr_standard"
BODY_TYPE"PLUMBING"
HDL_TAP"TRUE";
"B \NAC \NWC"1;
"S \NAC"
BN"2"145;
%"TAP"
"1","(-3250,6000)","0","mstr_standard","I163";
;
CDS_LIB"mstr_standard"
BODY_TYPE"PLUMBING"
HDL_TAP"TRUE";
"B \NAC \NWC"1;
"S \NAC"
BN"0"143;
%"TAP"
"1","(-3250,5950)","0","mstr_standard","I164";
;
CDS_LIB"mstr_standard"
BODY_TYPE"PLUMBING"
HDL_TAP"TRUE";
"B \NAC \NWC"1;
"S \NAC"
BN"1"144;
%"TAP"
"1","(-3250,5850)","0","mstr_standard","I165";
;
CDS_LIB"mstr_standard"
BODY_TYPE"PLUMBING"
HDL_TAP"TRUE";
"B \NAC \NWC"1;
"S \NAC"
BN"3"146;
%"TAP"
"1","(-3250,5800)","0","mstr_standard","I166";
;
CDS_LIB"mstr_standard"
BODY_TYPE"PLUMBING"
HDL_TAP"TRUE";
"B \NAC \NWC"1;
"S \NAC"
BN"4"147;
%"TAP"
"1","(-3250,5700)","0","mstr_standard","I167";
;
CDS_LIB"mstr_standard"
BODY_TYPE"PLUMBING"
HDL_TAP"TRUE";
"B \NAC \NWC"1;
"S \NAC"
BN"6"149;
%"TAP"
"1","(-3250,5750)","0","mstr_standard","I168";
;
CDS_LIB"mstr_standard"
BODY_TYPE"PLUMBING"
HDL_TAP"TRUE";
"B \NAC \NWC"1;
"S \NAC"
BN"5"148;
%"TAP"
"1","(-3250,5650)","0","mstr_standard","I169";
;
CDS_LIB"mstr_standard"
BODY_TYPE"PLUMBING"
HDL_TAP"TRUE";
"B \NAC \NWC"1;
"S \NAC"
BN"7"150;
%"TAP"
"1","(-3250,5550)","0","mstr_standard","I170";
;
CDS_LIB"mstr_standard"
BODY_TYPE"PLUMBING"
HDL_TAP"TRUE";
"B \NAC \NWC"1;
"S \NAC"
BN"8"151;
%"TAP"
"1","(-3250,5500)","0","mstr_standard","I171";
;
CDS_LIB"mstr_standard"
BODY_TYPE"PLUMBING"
HDL_TAP"TRUE";
"B \NAC \NWC"1;
"S \NAC"
BN"9"152;
%"TAP"
"1","(-3250,5450)","0","mstr_standard","I172";
;
CDS_LIB"mstr_standard"
BODY_TYPE"PLUMBING"
HDL_TAP"TRUE";
"B \NAC \NWC"1;
"S \NAC"
BN"10"153;
%"TAP"
"1","(-3250,5400)","0","mstr_standard","I173";
;
CDS_LIB"mstr_standard"
BODY_TYPE"PLUMBING"
HDL_TAP"TRUE";
"B \NAC \NWC"1;
"S \NAC"
BN"11"154;
%"TAP"
"1","(-3250,5350)","0","mstr_standard","I174";
;
CDS_LIB"mstr_standard"
BODY_TYPE"PLUMBING"
HDL_TAP"TRUE";
"B \NAC \NWC"1;
"S \NAC"
BN"12"155;
%"TAP"
"1","(-3250,5300)","0","mstr_standard","I175";
;
CDS_LIB"mstr_standard"
BODY_TYPE"PLUMBING"
HDL_TAP"TRUE";
"B \NAC \NWC"1;
"S \NAC"
BN"13"156;
%"TAP"
"1","(-3250,5250)","0","mstr_standard","I176";
;
CDS_LIB"mstr_standard"
BODY_TYPE"PLUMBING"
HDL_TAP"TRUE";
"B \NAC \NWC"1;
"S \NAC"
BN"14"157;
%"TAP"
"1","(-3250,5200)","0","mstr_standard","I177";
;
CDS_LIB"mstr_standard"
BODY_TYPE"PLUMBING"
HDL_TAP"TRUE";
"B \NAC \NWC"1;
"S \NAC"
BN"15"158;
%"TAP"
"1","(-3250,5000)","0","mstr_standard","I178";
;
CDS_LIB"mstr_standard"
BODY_TYPE"PLUMBING"
HDL_TAP"TRUE";
"B \NAC \NWC"1;
"S \NAC"
BN"18"129;
%"TAP"
"1","(-3250,5100)","0","mstr_standard","I179";
;
CDS_LIB"mstr_standard"
BODY_TYPE"PLUMBING"
HDL_TAP"TRUE";
"B \NAC \NWC"1;
"S \NAC"
BN"16"127;
%"TAP"
"1","(-3250,5050)","0","mstr_standard","I180";
;
CDS_LIB"mstr_standard"
BODY_TYPE"PLUMBING"
HDL_TAP"TRUE";
"B \NAC \NWC"1;
"S \NAC"
BN"17"128;
%"TAP"
"1","(-3250,4950)","0","mstr_standard","I181";
;
CDS_LIB"mstr_standard"
BODY_TYPE"PLUMBING"
HDL_TAP"TRUE";
"B \NAC \NWC"1;
"S \NAC"
BN"19"130;
%"TAP"
"1","(-3250,4900)","0","mstr_standard","I182";
;
CDS_LIB"mstr_standard"
BODY_TYPE"PLUMBING"
HDL_TAP"TRUE";
"B \NAC \NWC"1;
"S \NAC"
BN"20"131;
%"TAP"
"1","(-3250,4800)","0","mstr_standard","I183";
;
CDS_LIB"mstr_standard"
BODY_TYPE"PLUMBING"
HDL_TAP"TRUE";
"B \NAC \NWC"1;
"S \NAC"
BN"22"126;
%"TAP"
"1","(-3250,4850)","0","mstr_standard","I184";
;
CDS_LIB"mstr_standard"
BODY_TYPE"PLUMBING"
HDL_TAP"TRUE";
"B \NAC \NWC"1;
"S \NAC"
BN"21"132;
%"TAP"
"1","(-3250,4750)","0","mstr_standard","I185";
;
CDS_LIB"mstr_standard"
BODY_TYPE"PLUMBING"
HDL_TAP"TRUE";
"B \NAC \NWC"1;
"S \NAC"
BN"23"133;
%"TAP"
"1","(-3250,4650)","0","mstr_standard","I186";
;
CDS_LIB"mstr_standard"
BODY_TYPE"PLUMBING"
HDL_TAP"TRUE";
"B \NAC \NWC"1;
"S \NAC"
BN"24"134;
%"TAP"
"1","(-3250,4500)","0","mstr_standard","I187";
;
CDS_LIB"mstr_standard"
BODY_TYPE"PLUMBING"
HDL_TAP"TRUE";
"B \NAC \NWC"1;
"S \NAC"
BN"27"137;
%"TAP"
"1","(-3250,4550)","0","mstr_standard","I188";
;
CDS_LIB"mstr_standard"
BODY_TYPE"PLUMBING"
HDL_TAP"TRUE";
"B \NAC \NWC"1;
"S \NAC"
BN"26"136;
%"TAP"
"1","(-3250,4600)","0","mstr_standard","I189";
;
CDS_LIB"mstr_standard"
BODY_TYPE"PLUMBING"
HDL_TAP"TRUE";
"B \NAC \NWC"1;
"S \NAC"
BN"25"135;
%"TAP"
"1","(-3250,4450)","0","mstr_standard","I190";
;
CDS_LIB"mstr_standard"
BODY_TYPE"PLUMBING"
HDL_TAP"TRUE";
"B \NAC \NWC"1;
"S \NAC"
BN"28"138;
%"TAP"
"1","(-3250,4400)","0","mstr_standard","I191";
;
CDS_LIB"mstr_standard"
BODY_TYPE"PLUMBING"
HDL_TAP"TRUE";
"B \NAC \NWC"1;
"S \NAC"
BN"29"139;
%"TAP"
"1","(-3250,4300)","0","mstr_standard","I192";
;
CDS_LIB"mstr_standard"
BODY_TYPE"PLUMBING"
HDL_TAP"TRUE";
"B \NAC \NWC"1;
"S \NAC"
BN"31"124;
%"TAP"
"1","(-3250,4350)","0","mstr_standard","I193";
;
CDS_LIB"mstr_standard"
BODY_TYPE"PLUMBING"
HDL_TAP"TRUE";
"B \NAC \NWC"1;
"S \NAC"
BN"30"140;
%"TAP"
"1","(-3250,4200)","0","mstr_standard","I194";
;
CDS_LIB"mstr_standard"
BODY_TYPE"PLUMBING"
HDL_TAP"TRUE";
"B \NAC \NWC"2;
"S \NAC"
BN"0"125;
%"TAP"
"1","(-3250,4150)","0","mstr_standard","I195";
;
CDS_LIB"mstr_standard"
BODY_TYPE"PLUMBING"
HDL_TAP"TRUE";
"B \NAC \NWC"2;
"S \NAC"
BN"1"141;
%"TAP"
"1","(-3250,4100)","0","mstr_standard","I196";
;
CDS_LIB"mstr_standard"
BODY_TYPE"PLUMBING"
HDL_TAP"TRUE";
"B \NAC \NWC"2;
"S \NAC"
BN"2"142;
%"TAP"
"1","(-3250,4050)","0","mstr_standard","I198";
;
CDS_LIB"mstr_standard"
BODY_TYPE"PLUMBING"
HDL_TAP"TRUE";
"B \NAC \NWC"2;
"S \NAC"
BN"3"109;
%"TAP"
"1","(-3250,4000)","0","mstr_standard","I199";
;
CDS_LIB"mstr_standard"
BODY_TYPE"PLUMBING"
HDL_TAP"TRUE";
"B \NAC \NWC"2;
"S \NAC"
BN"4"110;
%"TAP"
"1","(-3250,3850)","0","mstr_standard","I200";
;
CDS_LIB"mstr_standard"
BODY_TYPE"PLUMBING"
HDL_TAP"TRUE";
"B \NAC \NWC"2;
"S \NAC"
BN"7"106;
%"TAP"
"1","(-3250,3900)","0","mstr_standard","I201";
;
CDS_LIB"mstr_standard"
BODY_TYPE"PLUMBING"
HDL_TAP"TRUE";
"B \NAC \NWC"2;
"S \NAC"
BN"6"107;
%"TAP"
"1","(-3250,3950)","0","mstr_standard","I202";
;
CDS_LIB"mstr_standard"
BODY_TYPE"PLUMBING"
HDL_TAP"TRUE";
"B \NAC \NWC"2;
"S \NAC"
BN"5"108;
%"TAP"
"1","(-3250,3750)","0","mstr_standard","I203";
;
CDS_LIB"mstr_standard"
BODY_TYPE"PLUMBING"
HDL_TAP"TRUE";
"B \NAC \NWC"2;
"S \NAC"
BN"8"111;
%"TAP"
"1","(-3250,3700)","0","mstr_standard","I204";
;
CDS_LIB"mstr_standard"
BODY_TYPE"PLUMBING"
HDL_TAP"TRUE";
"B \NAC \NWC"2;
"S \NAC"
BN"9"112;
%"TAP"
"1","(-3250,3650)","0","mstr_standard","I205";
;
CDS_LIB"mstr_standard"
BODY_TYPE"PLUMBING"
HDL_TAP"TRUE";
"B \NAC \NWC"2;
"S \NAC"
BN"10"113;
%"TAP"
"1","(-3250,3600)","0","mstr_standard","I206";
;
CDS_LIB"mstr_standard"
BODY_TYPE"PLUMBING"
HDL_TAP"TRUE";
"B \NAC \NWC"2;
"S \NAC"
BN"11"114;
%"TAP"
"1","(-3250,3500)","0","mstr_standard","I207";
;
CDS_LIB"mstr_standard"
BODY_TYPE"PLUMBING"
HDL_TAP"TRUE";
"B \NAC \NWC"2;
"S \NAC"
BN"13"116;
%"TAP"
"1","(-3250,3550)","0","mstr_standard","I208";
;
CDS_LIB"mstr_standard"
BODY_TYPE"PLUMBING"
HDL_TAP"TRUE";
"B \NAC \NWC"2;
"S \NAC"
BN"12"115;
%"TAP"
"1","(-3250,3400)","0","mstr_standard","I209";
;
CDS_LIB"mstr_standard"
BODY_TYPE"PLUMBING"
HDL_TAP"TRUE";
"B \NAC \NWC"2;
"S \NAC"
BN"15"118;
%"TAP"
"1","(-3250,3450)","0","mstr_standard","I210";
;
CDS_LIB"mstr_standard"
BODY_TYPE"PLUMBING"
HDL_TAP"TRUE";
"B \NAC \NWC"2;
"S \NAC"
BN"14"117;
%"TAP"
"1","(-3250,3250)","0","mstr_standard","I211";
;
CDS_LIB"mstr_standard"
BODY_TYPE"PLUMBING"
HDL_TAP"TRUE";
"B \NAC \NWC"2;
"S \NAC"
BN"17"120;
%"TAP"
"1","(-3250,3300)","0","mstr_standard","I212";
;
CDS_LIB"mstr_standard"
BODY_TYPE"PLUMBING"
HDL_TAP"TRUE";
"B \NAC \NWC"2;
"S \NAC"
BN"16"119;
%"TAP"
"1","(-3250,3200)","0","mstr_standard","I213";
;
CDS_LIB"mstr_standard"
BODY_TYPE"PLUMBING"
HDL_TAP"TRUE";
"B \NAC \NWC"2;
"S \NAC"
BN"18"121;
%"TAP"
"1","(-3250,3100)","0","mstr_standard","I214";
;
CDS_LIB"mstr_standard"
BODY_TYPE"PLUMBING"
HDL_TAP"TRUE";
"B \NAC \NWC"2;
"S \NAC"
BN"20"123;
%"TAP"
"1","(-3250,3150)","0","mstr_standard","I215";
;
CDS_LIB"mstr_standard"
BODY_TYPE"PLUMBING"
HDL_TAP"TRUE";
"B \NAC \NWC"2;
"S \NAC"
BN"19"122;
%"TAP"
"1","(-3250,2950)","0","mstr_standard","I216";
;
CDS_LIB"mstr_standard"
BODY_TYPE"PLUMBING"
HDL_TAP"TRUE";
"B \NAC \NWC"2;
"S \NAC"
BN"23"97;
%"TAP"
"1","(-3250,3000)","0","mstr_standard","I217";
;
CDS_LIB"mstr_standard"
BODY_TYPE"PLUMBING"
HDL_TAP"TRUE";
"B \NAC \NWC"2;
"S \NAC"
BN"22"96;
%"TAP"
"1","(-3250,3050)","0","mstr_standard","I218";
;
CDS_LIB"mstr_standard"
BODY_TYPE"PLUMBING"
HDL_TAP"TRUE";
"B \NAC \NWC"2;
"S \NAC"
BN"21"95;
%"TAP"
"1","(-3250,2850)","0","mstr_standard","I219";
;
CDS_LIB"mstr_standard"
BODY_TYPE"PLUMBING"
HDL_TAP"TRUE";
"B \NAC \NWC"2;
"S \NAC"
BN"24"98;
%"TAP"
"1","(-3250,2800)","0","mstr_standard","I220";
;
CDS_LIB"mstr_standard"
BODY_TYPE"PLUMBING"
HDL_TAP"TRUE";
"B \NAC \NWC"2;
"S \NAC"
BN"25"99;
%"TAP"
"1","(-3250,2750)","0","mstr_standard","I221";
;
CDS_LIB"mstr_standard"
BODY_TYPE"PLUMBING"
HDL_TAP"TRUE";
"B \NAC \NWC"2;
"S \NAC"
BN"26"100;
%"TAP"
"1","(-3250,2700)","0","mstr_standard","I222";
;
CDS_LIB"mstr_standard"
BODY_TYPE"PLUMBING"
HDL_TAP"TRUE";
"B \NAC \NWC"2;
"S \NAC"
BN"27"101;
%"TAP"
"1","(-3250,2650)","0","mstr_standard","I223";
;
CDS_LIB"mstr_standard"
BODY_TYPE"PLUMBING"
HDL_TAP"TRUE";
"B \NAC \NWC"2;
"S \NAC"
BN"28"102;
%"TAP"
"1","(-3250,2600)","0","mstr_standard","I224";
;
CDS_LIB"mstr_standard"
BODY_TYPE"PLUMBING"
HDL_TAP"TRUE";
"B \NAC \NWC"2;
"S \NAC"
BN"29"103;
%"TAP"
"1","(-3250,2550)","0","mstr_standard","I225";
;
CDS_LIB"mstr_standard"
BODY_TYPE"PLUMBING"
HDL_TAP"TRUE";
"B \NAC \NWC"2;
"S \NAC"
BN"30"104;
%"TAP"
"1","(-3250,2500)","0","mstr_standard","I226";
;
CDS_LIB"mstr_standard"
BODY_TYPE"PLUMBING"
HDL_TAP"TRUE";
"B \NAC \NWC"2;
"S \NAC"
BN"31"105;
%"TAP"
"1","(-3250,2400)","0","mstr_standard","I227";
;
CDS_LIB"mstr_standard"
BODY_TYPE"PLUMBING"
HDL_TAP"TRUE";
"B \NAC \NWC"3;
"S \NAC"
BN"0"87;
%"TAP"
"1","(-3250,2350)","0","mstr_standard","I228";
;
CDS_LIB"mstr_standard"
BODY_TYPE"PLUMBING"
HDL_TAP"TRUE";
"B \NAC \NWC"3;
"S \NAC"
BN"1"88;
%"TAP"
"1","(-3250,2300)","0","mstr_standard","I229";
;
CDS_LIB"mstr_standard"
BODY_TYPE"PLUMBING"
HDL_TAP"TRUE";
"B \NAC \NWC"3;
"S \NAC"
BN"2"89;
%"TAP"
"1","(-3250,2250)","0","mstr_standard","I230";
;
CDS_LIB"mstr_standard"
BODY_TYPE"PLUMBING"
HDL_TAP"TRUE";
"B \NAC \NWC"3;
"S \NAC"
BN"3"90;
%"TAP"
"1","(-3250,2200)","0","mstr_standard","I231";
;
CDS_LIB"mstr_standard"
BODY_TYPE"PLUMBING"
HDL_TAP"TRUE";
"B \NAC \NWC"3;
"S \NAC"
BN"4"91;
%"TAP"
"1","(-3250,2100)","0","mstr_standard","I232";
;
CDS_LIB"mstr_standard"
BODY_TYPE"PLUMBING"
HDL_TAP"TRUE";
"B \NAC \NWC"3;
"S \NAC"
BN"6"93;
%"TAP"
"1","(-3250,2150)","0","mstr_standard","I233";
;
CDS_LIB"mstr_standard"
BODY_TYPE"PLUMBING"
HDL_TAP"TRUE";
"B \NAC \NWC"3;
"S \NAC"
BN"5"92;
%"TAP"
"1","(-3250,2050)","0","mstr_standard","I234";
;
CDS_LIB"mstr_standard"
BODY_TYPE"PLUMBING"
HDL_TAP"TRUE";
"B \NAC \NWC"3;
"S \NAC"
BN"7"94;
%"TAP"
"1","(-3250,1950)","0","mstr_standard","I236";
;
CDS_LIB"mstr_standard"
BODY_TYPE"PLUMBING"
HDL_TAP"TRUE";
"B \NAC \NWC"4;
"S \NAC"
BN"0"79;
%"TAP"
"1","(-3250,1800)","0","mstr_standard","I237";
;
CDS_LIB"mstr_standard"
BODY_TYPE"PLUMBING"
HDL_TAP"TRUE";
"B \NAC \NWC"4;
"S \NAC"
BN"3"82;
%"TAP"
"1","(-3250,1900)","0","mstr_standard","I238";
;
CDS_LIB"mstr_standard"
BODY_TYPE"PLUMBING"
HDL_TAP"TRUE";
"B \NAC \NWC"4;
"S \NAC"
BN"1"80;
%"TAP"
"1","(-3250,1850)","0","mstr_standard","I239";
;
CDS_LIB"mstr_standard"
BODY_TYPE"PLUMBING"
HDL_TAP"TRUE";
"B \NAC \NWC"4;
"S \NAC"
BN"2"81;
%"TAP"
"1","(-3250,1750)","0","mstr_standard","I240";
;
CDS_LIB"mstr_standard"
BODY_TYPE"PLUMBING"
HDL_TAP"TRUE";
"B \NAC \NWC"4;
"S \NAC"
BN"4"83;
%"TAP"
"1","(-3250,1700)","0","mstr_standard","I241";
;
CDS_LIB"mstr_standard"
BODY_TYPE"PLUMBING"
HDL_TAP"TRUE";
"B \NAC \NWC"4;
"S \NAC"
BN"5"84;
%"TAP"
"1","(-3250,1650)","0","mstr_standard","I242";
;
CDS_LIB"mstr_standard"
BODY_TYPE"PLUMBING"
HDL_TAP"TRUE";
"B \NAC \NWC"4;
"S \NAC"
BN"6"85;
%"TAP"
"1","(-3250,1600)","0","mstr_standard","I243";
;
CDS_LIB"mstr_standard"
BODY_TYPE"PLUMBING"
HDL_TAP"TRUE";
"B \NAC \NWC"4;
"S \NAC"
BN"7"86;
%"TAP"
"1","(-5675,5900)","2","mstr_standard","I244";
;
CDS_LIB"mstr_standard"
BODY_TYPE"PLUMBING"
HDL_TAP"TRUE";
"B \NAC \NWC"5;
"S \NAC"
BN"1"76;
%"TAP"
"1","(-5675,6000)","2","mstr_standard","I245";
;
CDS_LIB"mstr_standard"
BODY_TYPE"PLUMBING"
HDL_TAP"TRUE";
"B \NAC \NWC"5;
"S \NAC"
BN"0"75;
%"TAP"
"1","(-5675,5800)","2","mstr_standard","I246";
;
CDS_LIB"mstr_standard"
BODY_TYPE"PLUMBING"
HDL_TAP"TRUE";
"B \NAC \NWC"5;
"S \NAC"
BN"2"77;
%"TAP"
"1","(-5675,5700)","2","mstr_standard","I247";
;
CDS_LIB"mstr_standard"
BODY_TYPE"PLUMBING"
HDL_TAP"TRUE";
"B \NAC \NWC"5;
"S \NAC"
BN"3"78;
%"TAP"
"1","(-5875,5950)","2","mstr_standard","I248";
;
CDS_LIB"mstr_standard"
BODY_TYPE"PLUMBING"
HDL_TAP"TRUE";
"B \NAC \NWC"9;
"S \NAC"
BN"0"64;
%"TAP"
"1","(-5875,5650)","2","mstr_standard","I249";
;
CDS_LIB"mstr_standard"
BODY_TYPE"PLUMBING"
HDL_TAP"TRUE";
"B \NAC \NWC"9;
"S \NAC"
BN"3"67;
%"TAP"
"1","(-5875,5750)","2","mstr_standard","I250";
;
CDS_LIB"mstr_standard"
BODY_TYPE"PLUMBING"
HDL_TAP"TRUE";
"B \NAC \NWC"9;
"S \NAC"
BN"2"66;
%"TAP"
"1","(-5875,5850)","2","mstr_standard","I251";
;
CDS_LIB"mstr_standard"
BODY_TYPE"PLUMBING"
HDL_TAP"TRUE";
"B \NAC \NWC"9;
"S \NAC"
BN"1"65;
%"TAP"
"1","(-5675,5600)","2","mstr_standard","I252";
;
CDS_LIB"mstr_standard"
BODY_TYPE"PLUMBING"
HDL_TAP"TRUE";
"B \NAC \NWC"5;
"S \NAC"
BN"4"70;
%"TAP"
"1","(-5675,5500)","2","mstr_standard","I253";
;
CDS_LIB"mstr_standard"
BODY_TYPE"PLUMBING"
HDL_TAP"TRUE";
"B \NAC \NWC"5;
"S \NAC"
BN"5"72;
%"TAP"
"1","(-5675,5400)","2","mstr_standard","I254";
;
CDS_LIB"mstr_standard"
BODY_TYPE"PLUMBING"
HDL_TAP"TRUE";
"B \NAC \NWC"5;
"S \NAC"
BN"6"73;
%"TAP"
"1","(-5675,5300)","2","mstr_standard","I255";
;
CDS_LIB"mstr_standard"
BODY_TYPE"PLUMBING"
HDL_TAP"TRUE";
"B \NAC \NWC"5;
"S \NAC"
BN"7"74;
%"TAP"
"1","(-5675,5200)","2","mstr_standard","I256";
;
CDS_LIB"mstr_standard"
BODY_TYPE"PLUMBING"
HDL_TAP"TRUE";
"B \NAC \NWC"5;
"S \NAC"
BN"8"71;
%"TAP"
"1","(-5875,5450)","2","mstr_standard","I257";
;
CDS_LIB"mstr_standard"
BODY_TYPE"PLUMBING"
HDL_TAP"TRUE";
"B \NAC \NWC"9;
"S \NAC"
BN"5"62;
%"TAP"
"1","(-5875,5550)","2","mstr_standard","I258";
;
CDS_LIB"mstr_standard"
BODY_TYPE"PLUMBING"
HDL_TAP"TRUE";
"B \NAC \NWC"9;
"S \NAC"
BN"4"61;
%"TAP"
"1","(-5875,5150)","2","mstr_standard","I259";
;
CDS_LIB"mstr_standard"
BODY_TYPE"PLUMBING"
HDL_TAP"TRUE";
"B \NAC \NWC"9;
"S \NAC"
BN"8"69;
%"TAP"
"1","(-5875,5350)","2","mstr_standard","I260";
;
CDS_LIB"mstr_standard"
BODY_TYPE"PLUMBING"
HDL_TAP"TRUE";
"B \NAC \NWC"9;
"S \NAC"
BN"6"68;
%"TAP"
"1","(-5875,5250)","2","mstr_standard","I261";
;
CDS_LIB"mstr_standard"
BODY_TYPE"PLUMBING"
HDL_TAP"TRUE";
"B \NAC \NWC"9;
"S \NAC"
BN"7"63;
%"TAP"
"1","(-5675,4950)","2","mstr_standard","I262";
;
CDS_LIB"mstr_standard"
BODY_TYPE"PLUMBING"
HDL_TAP"TRUE";
"B \NAC \NWC"6;
"S \NAC"
BN"0"57;
%"TAP"
"1","(-5675,5100)","2","mstr_standard","I263";
;
CDS_LIB"mstr_standard"
BODY_TYPE"PLUMBING"
HDL_TAP"TRUE";
"B \NAC \NWC"5;
"S \NAC"
BN"9"56;
%"TAP"
"1","(-5675,4850)","2","mstr_standard","I264";
;
CDS_LIB"mstr_standard"
BODY_TYPE"PLUMBING"
HDL_TAP"TRUE";
"B \NAC \NWC"6;
"S \NAC"
BN"1"58;
%"TAP"
"1","(-5675,4750)","2","mstr_standard","I265";
;
CDS_LIB"mstr_standard"
BODY_TYPE"PLUMBING"
HDL_TAP"TRUE";
"B \NAC \NWC"6;
"S \NAC"
BN"2"59;
%"TAP"
"1","(-5675,4650)","2","mstr_standard","I266";
;
CDS_LIB"mstr_standard"
BODY_TYPE"PLUMBING"
HDL_TAP"TRUE";
"B \NAC \NWC"6;
"S \NAC"
BN"3"60;
%"TAP"
"1","(-5875,4900)","2","mstr_standard","I267";
;
CDS_LIB"mstr_standard"
BODY_TYPE"PLUMBING"
HDL_TAP"TRUE";
"B \NAC \NWC"10;
"S \NAC"
BN"0"42;
%"TAP"
"1","(-5875,5050)","2","mstr_standard","I268";
;
CDS_LIB"mstr_standard"
BODY_TYPE"PLUMBING"
HDL_TAP"TRUE";
"B \NAC \NWC"9;
"S \NAC"
BN"9"43;
%"TAP"
"1","(-5875,4800)","2","mstr_standard","I269";
;
CDS_LIB"mstr_standard"
BODY_TYPE"PLUMBING"
HDL_TAP"TRUE";
"B \NAC \NWC"10;
"S \NAC"
BN"1"44;
%"TAP"
"1","(-5875,4700)","2","mstr_standard","I270";
;
CDS_LIB"mstr_standard"
BODY_TYPE"PLUMBING"
HDL_TAP"TRUE";
"B \NAC \NWC"10;
"S \NAC"
BN"2"45;
%"TAP"
"1","(-5675,4550)","2","mstr_standard","I271";
;
CDS_LIB"mstr_standard"
BODY_TYPE"PLUMBING"
HDL_TAP"TRUE";
"B \NAC \NWC"6;
"S \NAC"
BN"4"52;
%"TAP"
"1","(-5675,4450)","2","mstr_standard","I272";
;
CDS_LIB"mstr_standard"
BODY_TYPE"PLUMBING"
HDL_TAP"TRUE";
"B \NAC \NWC"6;
"S \NAC"
BN"5"51;
%"TAP"
"1","(-5875,4600)","2","mstr_standard","I273";
;
CDS_LIB"mstr_standard"
BODY_TYPE"PLUMBING"
HDL_TAP"TRUE";
"B \NAC \NWC"10;
"S \NAC"
BN"3"46;
%"TAP"
"1","(-5675,4350)","2","mstr_standard","I274";
;
CDS_LIB"mstr_standard"
BODY_TYPE"PLUMBING"
HDL_TAP"TRUE";
"B \NAC \NWC"6;
"S \NAC"
BN"6"53;
%"TAP"
"1","(-5675,4250)","2","mstr_standard","I275";
;
CDS_LIB"mstr_standard"
BODY_TYPE"PLUMBING"
HDL_TAP"TRUE";
"B \NAC \NWC"6;
"S \NAC"
BN"7"54;
%"TAP"
"1","(-5675,4150)","2","mstr_standard","I276";
;
CDS_LIB"mstr_standard"
BODY_TYPE"PLUMBING"
HDL_TAP"TRUE";
"B \NAC \NWC"6;
"S \NAC"
BN"8"55;
%"TAP"
"1","(-5875,4400)","2","mstr_standard","I277";
;
CDS_LIB"mstr_standard"
BODY_TYPE"PLUMBING"
HDL_TAP"TRUE";
"B \NAC \NWC"10;
"S \NAC"
BN"5"47;
%"TAP"
"1","(-5875,4500)","2","mstr_standard","I278";
;
CDS_LIB"mstr_standard"
BODY_TYPE"PLUMBING"
HDL_TAP"TRUE";
"B \NAC \NWC"10;
"S \NAC"
BN"4"41;
%"TAP"
"1","(-5875,4100)","2","mstr_standard","I279";
;
CDS_LIB"mstr_standard"
BODY_TYPE"PLUMBING"
HDL_TAP"TRUE";
"B \NAC \NWC"10;
"S \NAC"
BN"8"50;
%"TAP"
"1","(-5875,4200)","2","mstr_standard","I280";
;
CDS_LIB"mstr_standard"
BODY_TYPE"PLUMBING"
HDL_TAP"TRUE";
"B \NAC \NWC"10;
"S \NAC"
BN"7"49;
%"TAP"
"1","(-5875,4300)","2","mstr_standard","I281";
;
CDS_LIB"mstr_standard"
BODY_TYPE"PLUMBING"
HDL_TAP"TRUE";
"B \NAC \NWC"10;
"S \NAC"
BN"6"48;
%"TAP"
"1","(-5675,4050)","2","mstr_standard","I286";
;
CDS_LIB"mstr_standard"
BODY_TYPE"PLUMBING"
HDL_TAP"TRUE";
"B \NAC \NWC"6;
"S \NAC"
BN"9"40;
%"TAP"
"1","(-5875,3850)","2","mstr_standard","I287";
;
CDS_LIB"mstr_standard"
BODY_TYPE"PLUMBING"
HDL_TAP"TRUE";
"B \NAC \NWC"8;
"S \NAC"
BN"0"27;
%"TAP"
"1","(-5875,4000)","2","mstr_standard","I288";
;
CDS_LIB"mstr_standard"
BODY_TYPE"PLUMBING"
HDL_TAP"TRUE";
"B \NAC \NWC"10;
"S \NAC"
BN"9"39;
%"TAP"
"1","(-5875,3700)","2","mstr_standard","I289";
;
CDS_LIB"mstr_standard"
BODY_TYPE"PLUMBING"
HDL_TAP"TRUE";
"B \NAC \NWC"8;
"S \NAC"
BN"3"30;
%"TAP"
"1","(-5875,3750)","2","mstr_standard","I290";
;
CDS_LIB"mstr_standard"
BODY_TYPE"PLUMBING"
HDL_TAP"TRUE";
"B \NAC \NWC"8;
"S \NAC"
BN"2"29;
%"TAP"
"1","(-5875,3800)","2","mstr_standard","I291";
;
CDS_LIB"mstr_standard"
BODY_TYPE"PLUMBING"
HDL_TAP"TRUE";
"B \NAC \NWC"8;
"S \NAC"
BN"1"28;
%"TAP"
"1","(-5875,3650)","2","mstr_standard","I292";
;
CDS_LIB"mstr_standard"
BODY_TYPE"PLUMBING"
HDL_TAP"TRUE";
"B \NAC \NWC"8;
"S \NAC"
BN"4"31;
%"TAP"
"1","(-5875,3600)","2","mstr_standard","I293";
;
CDS_LIB"mstr_standard"
BODY_TYPE"PLUMBING"
HDL_TAP"TRUE";
"B \NAC \NWC"8;
"S \NAC"
BN"5"25;
%"TAP"
"1","(-5875,3400)","2","mstr_standard","I294";
;
CDS_LIB"mstr_standard"
BODY_TYPE"PLUMBING"
HDL_TAP"TRUE";
"B \NAC \NWC"7;
"S \NAC"
BN"1"33;
%"TAP"
"1","(-5875,3350)","2","mstr_standard","I295";
;
CDS_LIB"mstr_standard"
BODY_TYPE"PLUMBING"
HDL_TAP"TRUE";
"B \NAC \NWC"7;
"S \NAC"
BN"2"34;
%"TAP"
"1","(-5875,3450)","2","mstr_standard","I296";
;
CDS_LIB"mstr_standard"
BODY_TYPE"PLUMBING"
HDL_TAP"TRUE";
"B \NAC \NWC"7;
"S \NAC"
BN"0"32;
%"TAP"
"1","(-5875,3550)","2","mstr_standard","I297";
;
CDS_LIB"mstr_standard"
BODY_TYPE"PLUMBING"
HDL_TAP"TRUE";
"B \NAC \NWC"8;
"S \NAC"
BN"6"26;
%"TAP"
"1","(-5875,3200)","2","mstr_standard","I298";
;
CDS_LIB"mstr_standard"
BODY_TYPE"PLUMBING"
HDL_TAP"TRUE";
"B \NAC \NWC"7;
"S \NAC"
BN"5"37;
%"TAP"
"1","(-5875,3150)","2","mstr_standard","I299";
;
CDS_LIB"mstr_standard"
BODY_TYPE"PLUMBING"
HDL_TAP"TRUE";
"B \NAC \NWC"7;
"S \NAC"
BN"6"38;
%"TAP"
"1","(-5875,3250)","2","mstr_standard","I300";
;
CDS_LIB"mstr_standard"
BODY_TYPE"PLUMBING"
HDL_TAP"TRUE";
"B \NAC \NWC"7;
"S \NAC"
BN"4"36;
%"TAP"
"1","(-5875,3300)","2","mstr_standard","I301";
;
CDS_LIB"mstr_standard"
BODY_TYPE"PLUMBING"
HDL_TAP"TRUE";
"B \NAC \NWC"7;
"S \NAC"
BN"3"35;
%"Q_RES"
"1","(-6800,2150)","0","pure_quanta","I314";
;
LOCATION"R384"
$SEC"1"
CDS_SEC"1"
TOLERANCE"1%"
VALUE"15   "
PART_NUMBER"CS01502FB11"
PACK_TYPE"0402LF"
CDS_LIB"pure_quanta"
WATTAGE"1/16W"
MATERIAL"CHIP";
"B"
$PN"2"13;
"A"
$PN"1"11;
END.
